(kicad_pcb
	(version 20260206)
	(generator "pcbnew")
	(generator_version "10.0")
	(general
		(thickness 1.6)
		(legacy_teardrops no)
	)
	(paper "A4")
	(title_block
		(title "v1-chassis-manager — T6M_CM_d_v01_1031_1645.brd")
		(comment 1 "Open CloudServer (Microsoft) / footprints 2052-2061 of 2512")
	)
	(layers
		(0 "F.Cu" signal "TOP")
		(4 "In1.Cu" signal "GND1")
		(6 "In2.Cu" signal "IN1")
		(8 "In3.Cu" signal "VCC1")
		(10 "In4.Cu" signal "VCC2")
		(12 "In5.Cu" signal "GND2")
		(14 "In6.Cu" signal "IN2")
		(16 "In7.Cu" signal "IN3")
		(18 "In8.Cu" signal "GND3")
		(2 "B.Cu" signal "BOTTOM")
		(9 "F.Adhes" user "F.Adhesive")
		(11 "B.Adhes" user "B.Adhesive")
		(13 "F.Paste" user "Package Geometry/Pastemask Top")
		(15 "B.Paste" user "Package Geometry/Pastemask Bottom")
		(5 "F.SilkS" user "Ref Des/Silkscreen Top")
		(7 "B.SilkS" user "Ref Des/Silkscreen Bottom")
		(1 "F.Mask" user "Board Geometry/Soldermask Top")
		(3 "B.Mask" user "Board Geometry/Soldermask Bottom")
		(17 "Dwgs.User" user "User.Drawings")
		(19 "Cmts.User" user "User.Comments")
		(21 "Eco1.User" user "User.Eco1")
		(23 "Eco2.User" user "User.Eco2")
		(25 "Edge.Cuts" user "Board Geometry/Outline")
		(27 "Margin" user)
		(31 "F.CrtYd" user "Package Geometry/Place Bound Top")
		(29 "B.CrtYd" user "Package Geometry/Place Bound Bottom")
		(35 "F.Fab" user "Ref Des/Assembly Top")
		(33 "B.Fab" user "Ref Des/Assembly Bottom")
	)
	(footprint ""
		(layer "B.Cu")
		(at 44.770802 -150.249382 90)
		(property "Reference" "C396"
			(at 7.961122 -12.448286 270)
			(unlocked yes)
			(layer "B.SilkS")
			(effects
				(font
					(size 0.7874 0.5842)
					(thickness 0.1524)
				)
				(justify left mirror)
			)
		)
		(property "Value" ""
			(at 0 0 90)
			(layer "B.Fab")
			(effects
				(font
					(size 1.27 1.27)
				)
				(justify mirror)
			)
		)
		(duplicate_pad_numbers_are_jumpers no)
		(fp_line
			(start 0.7874 -0.4064)
			(end -0.7874 -0.4064)
			(stroke
				(width 0.1524)
				(type default)
			)
			(layer "B.SilkS")
		)
		(fp_line
			(start -0.7874 -0.4064)
			(end -0.7874 0.4064)
			(stroke
				(width 0.1524)
				(type default)
			)
			(layer "B.SilkS")
		)
		(fp_line
			(start 0 0.381)
			(end 0 -0.381)
			(stroke
				(width 0.1524)
				(type default)
			)
			(layer "B.SilkS")
		)
		(fp_line
			(start 0.7874 0.4064)
			(end 0.7874 -0.4064)
			(stroke
				(width 0.1524)
				(type default)
			)
			(layer "B.SilkS")
		)
		(fp_line
			(start -0.7874 0.4064)
			(end 0.7874 0.4064)
			(stroke
				(width 0.1524)
				(type default)
			)
			(layer "B.SilkS")
		)
		(fp_poly
			(pts
				(xy 0.5334 0.254) (xy 0.635 0.254) (xy 0.635 0.2286) (xy 0.635 -0.254) (xy 0.5334 -0.254) (xy 0.5334 -0.2794)
				(xy -0.5334 -0.2794) (xy -0.5334 -0.254) (xy -0.635 -0.254) (xy -0.635 0.254) (xy -0.5334 0.254)
				(xy -0.5334 0.2794) (xy 0.508 0.2794) (xy 0.5334 0.2794)
			)
			(stroke
				(width 0)
				(type default)
			)
			(fill no)
			(layer "B.CrtYd")
		)
		(pad "1" smd rect
			(at -0.40005 0 270)
			(size 0.4572 0.508)
			(layers "B.Cu" "B.Mask" "B.Paste")
			(net "P3V3_NODE1")
		)
		(pad "2" smd rect
			(at 0.40005 0 270)
			(size 0.4572 0.508)
			(layers "B.Cu" "B.Mask" "B.Paste")
			(net "GND")
		)
	)
	(footprint ""
		(layer "B.Cu")
		(at 71.721472 -121.059702 90)
		(property "Reference" "R272"
			(at -7.400798 9.931908 270)
			(unlocked yes)
			(layer "B.SilkS")
			(effects
				(font
					(size 0.7874 0.5842)
					(thickness 0.1524)
				)
				(justify left mirror)
			)
		)
		(property "Value" ""
			(at 0 0 90)
			(layer "B.Fab")
			(effects
				(font
					(size 1.27 1.27)
				)
				(justify mirror)
			)
		)
		(duplicate_pad_numbers_are_jumpers no)
		(fp_line
			(start 0.7874 -0.4064)
			(end -0.7874 -0.4064)
			(stroke
				(width 0.1524)
				(type default)
			)
			(layer "B.SilkS")
		)
		(fp_line
			(start -0.7874 -0.4064)
			(end -0.7874 0.4064)
			(stroke
				(width 0.1524)
				(type default)
			)
			(layer "B.SilkS")
		)
		(fp_line
			(start 0.7874 0.4064)
			(end 0.7874 -0.4064)
			(stroke
				(width 0.1524)
				(type default)
			)
			(layer "B.SilkS")
		)
		(fp_line
			(start -0.7874 0.4064)
			(end 0.7874 0.4064)
			(stroke
				(width 0.1524)
				(type default)
			)
			(layer "B.SilkS")
		)
		(fp_poly
			(pts
				(xy 0.508 0.2794) (xy 0.508 0.2286) (xy 0.635 0.2286) (xy 0.635 -0.254) (xy 0.5334 -0.254) (xy 0.5334 -0.2794)
				(xy -0.5334 -0.2794) (xy -0.5334 -0.254) (xy -0.635 -0.254) (xy -0.635 0.254) (xy -0.5334 0.254)
				(xy -0.5334 0.2794)
			)
			(stroke
				(width 0)
				(type default)
			)
			(fill no)
			(layer "B.CrtYd")
		)
		(pad "1" smd rect
			(at -0.40005 0 270)
			(size 0.4572 0.508)
			(layers "B.Cu" "B.Mask" "B.Paste")
			(net "PE_SW_BMC_PERST_L")
		)
		(pad "2" smd rect
			(at 0.40005 0 270)
			(size 0.4572 0.508)
			(layers "B.Cu" "B.Mask" "B.Paste")
			(net "RST_BMC_NODE1_PERST_L")
		)
	)
	(footprint ""
		(layer "B.Cu")
		(at 137.970006 -41.50741 180)
		(property "Reference" "R1080"
			(at 4.172458 -18.349722 0)
			(unlocked yes)
			(layer "B.SilkS")
			(effects
				(font
					(size 0.7874 0.5842)
					(thickness 0.1524)
				)
				(justify left mirror)
			)
		)
		(property "Value" ""
			(at 0 0 0)
			(layer "B.Fab")
			(effects
				(font
					(size 1.27 1.27)
				)
				(justify mirror)
			)
		)
		(duplicate_pad_numbers_are_jumpers no)
		(fp_line
			(start 0.7874 0.4064)
			(end 0.7874 -0.4064)
			(stroke
				(width 0.1524)
				(type default)
			)
			(layer "B.SilkS")
		)
		(fp_line
			(start 0.7874 -0.4064)
			(end -0.7874 -0.4064)
			(stroke
				(width 0.1524)
				(type default)
			)
			(layer "B.SilkS")
		)
		(fp_line
			(start -0.7874 0.4064)
			(end 0.7874 0.4064)
			(stroke
				(width 0.1524)
				(type default)
			)
			(layer "B.SilkS")
		)
		(fp_line
			(start -0.7874 -0.4064)
			(end -0.7874 0.4064)
			(stroke
				(width 0.1524)
				(type default)
			)
			(layer "B.SilkS")
		)
		(fp_poly
			(pts
				(xy 0.508 0.2794) (xy 0.508 0.2286) (xy 0.635 0.2286) (xy 0.635 -0.254) (xy 0.5334 -0.254) (xy 0.5334 -0.2794)
				(xy -0.5334 -0.2794) (xy -0.5334 -0.254) (xy -0.635 -0.254) (xy -0.635 0.254) (xy -0.5334 0.254)
				(xy -0.5334 0.2794)
			)
			(stroke
				(width 0)
				(type default)
			)
			(fill no)
			(layer "B.CrtYd")
		)
		(pad "1" smd rect
			(at -0.40005 0)
			(size 0.4572 0.508)
			(layers "B.Cu" "B.Mask" "B.Paste")
			(net "SIO_JTAG_CPLD2_TDO")
		)
		(pad "2" smd rect
			(at 0.40005 0)
			(size 0.4572 0.508)
			(layers "B.Cu" "B.Mask" "B.Paste")
			(net "JTAG_CPLD2_TDO")
		)
	)
	(footprint ""
		(layer "B.Cu")
		(at 71.006208 -21.166582 90)
		(property "Reference" "C156"
			(at -5.87629 -0.810006 270)
			(unlocked yes)
			(layer "B.SilkS")
			(effects
				(font
					(size 0.7874 0.5842)
					(thickness 0.1524)
				)
				(justify left mirror)
			)
		)
		(property "Value" ""
			(at 0 0 90)
			(layer "B.Fab")
			(effects
				(font
					(size 1.27 1.27)
				)
				(justify mirror)
			)
		)
		(duplicate_pad_numbers_are_jumpers no)
		(fp_line
			(start 0.7874 -0.4064)
			(end -0.7874 -0.4064)
			(stroke
				(width 0.1524)
				(type default)
			)
			(layer "B.SilkS")
		)
		(fp_line
			(start -0.7874 -0.4064)
			(end -0.7874 0.4064)
			(stroke
				(width 0.1524)
				(type default)
			)
			(layer "B.SilkS")
		)
		(fp_line
			(start 0 0.381)
			(end 0 -0.381)
			(stroke
				(width 0.1524)
				(type default)
			)
			(layer "B.SilkS")
		)
		(fp_line
			(start 0.7874 0.4064)
			(end 0.7874 -0.4064)
			(stroke
				(width 0.1524)
				(type default)
			)
			(layer "B.SilkS")
		)
		(fp_line
			(start -0.7874 0.4064)
			(end 0.7874 0.4064)
			(stroke
				(width 0.1524)
				(type default)
			)
			(layer "B.SilkS")
		)
		(fp_poly
			(pts
				(xy 0.5334 0.254) (xy 0.635 0.254) (xy 0.635 0.2286) (xy 0.635 -0.254) (xy 0.5334 -0.254) (xy 0.5334 -0.2794)
				(xy -0.5334 -0.2794) (xy -0.5334 -0.254) (xy -0.635 -0.254) (xy -0.635 0.254) (xy -0.5334 0.254)
				(xy -0.5334 0.2794) (xy 0.508 0.2794) (xy 0.5334 0.2794)
			)
			(stroke
				(width 0)
				(type default)
			)
			(fill no)
			(layer "B.CrtYd")
		)
		(pad "1" smd rect
			(at -0.40005 0 270)
			(size 0.4572 0.508)
			(layers "B.Cu" "B.Mask" "B.Paste")
			(net "PV_VDDR_NODE1")
		)
		(pad "2" smd rect
			(at 0.40005 0 270)
			(size 0.4572 0.508)
			(layers "B.Cu" "B.Mask" "B.Paste")
			(net "GND")
		)
	)
	(footprint ""
		(layer "B.Cu")
		(at 152.562814 -67.232022 -90)
		(property "Reference" "C361"
			(at -0.02159 -5.145786 270)
			(unlocked yes)
			(layer "B.SilkS")
			(effects
				(font
					(size 0.7874 0.5842)
					(thickness 0.1524)
				)
				(justify left mirror)
			)
		)
		(property "Value" ""
			(at 0 0 90)
			(layer "B.Fab")
			(effects
				(font
					(size 1.27 1.27)
				)
				(justify mirror)
			)
		)
		(duplicate_pad_numbers_are_jumpers no)
		(fp_line
			(start -0.7874 0.4064)
			(end 0.7874 0.4064)
			(stroke
				(width 0.1524)
				(type default)
			)
			(layer "B.SilkS")
		)
		(fp_line
			(start 0.7874 0.4064)
			(end 0.7874 -0.4064)
			(stroke
				(width 0.1524)
				(type default)
			)
			(layer "B.SilkS")
		)
		(fp_line
			(start 0 0.381)
			(end 0 -0.381)
			(stroke
				(width 0.1524)
				(type default)
			)
			(layer "B.SilkS")
		)
		(fp_line
			(start -0.7874 -0.4064)
			(end -0.7874 0.4064)
			(stroke
				(width 0.1524)
				(type default)
			)
			(layer "B.SilkS")
		)
		(fp_line
			(start 0.7874 -0.4064)
			(end -0.7874 -0.4064)
			(stroke
				(width 0.1524)
				(type default)
			)
			(layer "B.SilkS")
		)
		(fp_poly
			(pts
				(xy 0.5334 0.254) (xy 0.635 0.254) (xy 0.635 0.2286) (xy 0.635 -0.254) (xy 0.5334 -0.254) (xy 0.5334 -0.2794)
				(xy -0.5334 -0.2794) (xy -0.5334 -0.254) (xy -0.635 -0.254) (xy -0.635 0.254) (xy -0.5334 0.254)
				(xy -0.5334 0.2794) (xy 0.508 0.2794) (xy 0.5334 0.2794)
			)
			(stroke
				(width 0)
				(type default)
			)
			(fill no)
			(layer "B.CrtYd")
		)
		(pad "1" smd rect
			(at -0.40005 0 90)
			(size 0.4572 0.508)
			(layers "B.Cu" "B.Mask" "B.Paste")
			(net "GND")
		)
		(pad "2" smd rect
			(at 0.40005 0 90)
			(size 0.4572 0.508)
			(layers "B.Cu" "B.Mask" "B.Paste")
			(net "P1V8_SATA_VAA1_NODE1")
		)
	)
	(footprint ""
		(layer "B.Cu")
		(at 56.86298 -62.869826)
		(property "Reference" "R28"
			(at -14.72438 29.520896 0)
			(unlocked yes)
			(layer "B.SilkS")
			(effects
				(font
					(size 0.7874 0.5842)
					(thickness 0.1524)
				)
				(justify left mirror)
			)
		)
		(property "Value" ""
			(at 0 0 0)
			(layer "B.Fab")
			(effects
				(font
					(size 1.27 1.27)
				)
				(justify mirror)
			)
		)
		(duplicate_pad_numbers_are_jumpers no)
		(fp_line
			(start -0.7874 -0.4064)
			(end -0.7874 0.4064)
			(stroke
				(width 0.1524)
				(type default)
			)
			(layer "B.SilkS")
		)
		(fp_line
			(start -0.7874 0.4064)
			(end 0.7874 0.4064)
			(stroke
				(width 0.1524)
				(type default)
			)
			(layer "B.SilkS")
		)
		(fp_line
			(start 0.7874 -0.4064)
			(end -0.7874 -0.4064)
			(stroke
				(width 0.1524)
				(type default)
			)
			(layer "B.SilkS")
		)
		(fp_line
			(start 0.7874 0.4064)
			(end 0.7874 -0.4064)
			(stroke
				(width 0.1524)
				(type default)
			)
			(layer "B.SilkS")
		)
		(fp_poly
			(pts
				(xy 0.508 0.2794) (xy 0.508 0.2286) (xy 0.635 0.2286) (xy 0.635 -0.254) (xy 0.5334 -0.254) (xy 0.5334 -0.2794)
				(xy -0.5334 -0.2794) (xy -0.5334 -0.254) (xy -0.635 -0.254) (xy -0.635 0.254) (xy -0.5334 0.254)
				(xy -0.5334 0.2794)
			)
			(stroke
				(width 0)
				(type default)
			)
			(fill no)
			(layer "B.CrtYd")
		)
		(pad "1" smd rect
			(at -0.40005 0 180)
			(size 0.4572 0.508)
			(layers "B.Cu" "B.Mask" "B.Paste")
			(net "GND")
		)
		(pad "2" smd rect
			(at 0.40005 0 180)
			(size 0.4572 0.508)
			(layers "B.Cu" "B.Mask" "B.Paste")
			(net "M_DDR3_NODE1_CMDPU")
		)
	)
	(footprint ""
		(layer "B.Cu")
		(at 115.010184 -162.251644)
		(property "Reference" "C590"
			(at 1.710436 2.15265 0)
			(unlocked yes)
			(layer "B.SilkS")
			(effects
				(font
					(size 0.7874 0.5842)
					(thickness 0.1524)
				)
				(justify left mirror)
			)
		)
		(property "Value" ""
			(at 0 0 0)
			(layer "B.Fab")
			(effects
				(font
					(size 1.27 1.27)
				)
				(justify mirror)
			)
		)
		(duplicate_pad_numbers_are_jumpers no)
		(fp_line
			(start -0.7874 -0.4064)
			(end -0.7874 0.4064)
			(stroke
				(width 0.1524)
				(type default)
			)
			(layer "B.SilkS")
		)
		(fp_line
			(start -0.7874 0.4064)
			(end 0.7874 0.4064)
			(stroke
				(width 0.1524)
				(type default)
			)
			(layer "B.SilkS")
		)
		(fp_line
			(start 0 0.381)
			(end 0 -0.381)
			(stroke
				(width 0.1524)
				(type default)
			)
			(layer "B.SilkS")
		)
		(fp_line
			(start 0.7874 -0.4064)
			(end -0.7874 -0.4064)
			(stroke
				(width 0.1524)
				(type default)
			)
			(layer "B.SilkS")
		)
		(fp_line
			(start 0.7874 0.4064)
			(end 0.7874 -0.4064)
			(stroke
				(width 0.1524)
				(type default)
			)
			(layer "B.SilkS")
		)
		(fp_poly
			(pts
				(xy 0.5334 0.254) (xy 0.635 0.254) (xy 0.635 0.2286) (xy 0.635 -0.254) (xy 0.5334 -0.254) (xy 0.5334 -0.2794)
				(xy -0.5334 -0.2794) (xy -0.5334 -0.254) (xy -0.635 -0.254) (xy -0.635 0.254) (xy -0.5334 0.254)
				(xy -0.5334 0.2794) (xy 0.508 0.2794) (xy 0.5334 0.2794)
			)
			(stroke
				(width 0)
				(type default)
			)
			(fill no)
			(layer "B.CrtYd")
		)
		(pad "1" smd rect
			(at -0.40005 0 180)
			(size 0.4572 0.508)
			(layers "B.Cu" "B.Mask" "B.Paste")
			(net "GND")
		)
		(pad "2" smd rect
			(at 0.40005 0 180)
			(size 0.4572 0.508)
			(layers "B.Cu" "B.Mask" "B.Paste")
			(net "I2C_COM3_SDA_RC")
		)
	)
	(footprint ""
		(layer "B.Cu")
		(at 128.701546 -37.258244 180)
		(property "Reference" "R1210"
			(at -0.438658 -7.56793 0)
			(unlocked yes)
			(layer "B.SilkS")
			(effects
				(font
					(size 0.7874 0.5842)
					(thickness 0.1524)
				)
				(justify left mirror)
			)
		)
		(property "Value" ""
			(at 0 0 0)
			(layer "B.Fab")
			(effects
				(font
					(size 1.27 1.27)
				)
				(justify mirror)
			)
		)
		(duplicate_pad_numbers_are_jumpers no)
		(fp_line
			(start 0.7874 0.4064)
			(end 0.7874 -0.4064)
			(stroke
				(width 0.1524)
				(type default)
			)
			(layer "B.SilkS")
		)
		(fp_line
			(start 0.7874 -0.4064)
			(end -0.7874 -0.4064)
			(stroke
				(width 0.1524)
				(type default)
			)
			(layer "B.SilkS")
		)
		(fp_line
			(start -0.7874 0.4064)
			(end 0.7874 0.4064)
			(stroke
				(width 0.1524)
				(type default)
			)
			(layer "B.SilkS")
		)
		(fp_line
			(start -0.7874 -0.4064)
			(end -0.7874 0.4064)
			(stroke
				(width 0.1524)
				(type default)
			)
			(layer "B.SilkS")
		)
		(fp_poly
			(pts
				(xy 0.508 0.2794) (xy 0.508 0.2286) (xy 0.635 0.2286) (xy 0.635 -0.254) (xy 0.5334 -0.254) (xy 0.5334 -0.2794)
				(xy -0.5334 -0.2794) (xy -0.5334 -0.254) (xy -0.635 -0.254) (xy -0.635 0.254) (xy -0.5334 0.254)
				(xy -0.5334 0.2794)
			)
			(stroke
				(width 0)
				(type default)
			)
			(fill no)
			(layer "B.CrtYd")
		)
		(pad "1" smd rect
			(at -0.40005 0)
			(size 0.4572 0.508)
			(layers "B.Cu" "B.Mask" "B.Paste")
			(net "SIO_JTAG_CPLD3_TCK")
		)
		(pad "2" smd rect
			(at 0.40005 0)
			(size 0.4572 0.508)
			(layers "B.Cu" "B.Mask" "B.Paste")
			(net "GND")
		)
	)
	(footprint ""
		(layer "B.Cu")
		(at 78.83144 -166.409624 180)
		(property "Reference" "R791"
			(at -30.555946 -20.918678 0)
			(unlocked yes)
			(layer "B.SilkS")
			(effects
				(font
					(size 0.7874 0.5842)
					(thickness 0.1524)
				)
				(justify left mirror)
			)
		)
		(property "Value" ""
			(at 0 0 0)
			(layer "B.Fab")
			(effects
				(font
					(size 1.27 1.27)
				)
				(justify mirror)
			)
		)
		(duplicate_pad_numbers_are_jumpers no)
		(fp_line
			(start 0.7874 0.4064)
			(end 0.7874 -0.4064)
			(stroke
				(width 0.1524)
				(type default)
			)
			(layer "B.SilkS")
		)
		(fp_line
			(start 0.7874 -0.4064)
			(end -0.7874 -0.4064)
			(stroke
				(width 0.1524)
				(type default)
			)
			(layer "B.SilkS")
		)
		(fp_line
			(start -0.7874 0.4064)
			(end 0.7874 0.4064)
			(stroke
				(width 0.1524)
				(type default)
			)
			(layer "B.SilkS")
		)
		(fp_line
			(start -0.7874 -0.4064)
			(end -0.7874 0.4064)
			(stroke
				(width 0.1524)
				(type default)
			)
			(layer "B.SilkS")
		)
		(fp_poly
			(pts
				(xy 0.508 0.2794) (xy 0.508 0.2286) (xy 0.635 0.2286) (xy 0.635 -0.254) (xy 0.5334 -0.254) (xy 0.5334 -0.2794)
				(xy -0.5334 -0.2794) (xy -0.5334 -0.254) (xy -0.635 -0.254) (xy -0.635 0.254) (xy -0.5334 0.254)
				(xy -0.5334 0.2794)
			)
			(stroke
				(width 0)
				(type default)
			)
			(fill no)
			(layer "B.CrtYd")
		)
		(pad "1" smd rect
			(at -0.40005 0)
			(size 0.4572 0.508)
			(layers "B.Cu" "B.Mask" "B.Paste")
			(net "UART_SW_S5_N")
		)
		(pad "2" smd rect
			(at 0.40005 0)
			(size 0.4572 0.508)
			(layers "B.Cu" "B.Mask" "B.Paste")
			(net "P3V3_NODE1")
		)
	)
	(footprint ""
		(layer "B.Cu")
		(at 42.78122 -159.13989 -90)
		(property "Reference" "C409"
			(at -7.11327 6.84276 270)
			(unlocked yes)
			(layer "B.SilkS")
			(effects
				(font
					(size 0.7874 0.5842)
					(thickness 0.1524)
				)
				(justify left mirror)
			)
		)
		(property "Value" ""
			(at 0 0 90)
			(layer "B.Fab")
			(effects
				(font
					(size 1.27 1.27)
				)
				(justify mirror)
			)
		)
		(duplicate_pad_numbers_are_jumpers no)
		(fp_line
			(start -0.7874 0.4064)
			(end 0.7874 0.4064)
			(stroke
				(width 0.1524)
				(type default)
			)
			(layer "B.SilkS")
		)
		(fp_line
			(start 0.7874 0.4064)
			(end 0.7874 -0.4064)
			(stroke
				(width 0.1524)
				(type default)
			)
			(layer "B.SilkS")
		)
		(fp_line
			(start 0 0.381)
			(end 0 -0.381)
			(stroke
				(width 0.1524)
				(type default)
			)
			(layer "B.SilkS")
		)
		(fp_line
			(start -0.7874 -0.4064)
			(end -0.7874 0.4064)
			(stroke
				(width 0.1524)
				(type default)
			)
			(layer "B.SilkS")
		)
		(fp_line
			(start 0.7874 -0.4064)
			(end -0.7874 -0.4064)
			(stroke
				(width 0.1524)
				(type default)
			)
			(layer "B.SilkS")
		)
		(fp_poly
			(pts
				(xy 0.5334 0.254) (xy 0.635 0.254) (xy 0.635 0.2286) (xy 0.635 -0.254) (xy 0.5334 -0.254) (xy 0.5334 -0.2794)
				(xy -0.5334 -0.2794) (xy -0.5334 -0.254) (xy -0.635 -0.254) (xy -0.635 0.254) (xy -0.5334 0.254)
				(xy -0.5334 0.2794) (xy 0.508 0.2794) (xy 0.5334 0.2794)
			)
			(stroke
				(width 0)
				(type default)
			)
			(fill no)
			(layer "B.CrtYd")
		)
		(pad "1" smd rect
			(at -0.40005 0 90)
			(size 0.4572 0.508)
			(layers "B.Cu" "B.Mask" "B.Paste")
			(net "P1V9_LAN1")
		)
		(pad "2" smd rect
			(at 0.40005 0 90)
			(size 0.4572 0.508)
			(layers "B.Cu" "B.Mask" "B.Paste")
			(net "GND")
		)
	)
)
